(kicad_pcb
	(version 20260206)
	(generator "pcbnew")
	(generator_version "10.0")
	(general
		(thickness 1.6)
		(legacy_teardrops no)
	)
	(paper "A4")
	(title_block
		(title "01162023_DA0F0TEBIF0_F0T_Expander_BD_F_brd_V02_OCP.brd")
		(comment 1 "Grand Teton / footprints 6172-6178 of 9728")
	)
	(layers
		(0 "F.Cu" signal "TOP")
		(4 "In1.Cu" signal "GND")
		(6 "In2.Cu" signal "VCC")
		(8 "In3.Cu" signal "VCC1")
		(10 "In4.Cu" signal "GND1")
		(12 "In5.Cu" signal "IN1")
		(14 "In6.Cu" signal "GND2")
		(16 "In7.Cu" signal "IN2")
		(18 "In8.Cu" signal "GND3")
		(20 "In9.Cu" signal "IN3")
		(22 "In10.Cu" signal "GND4")
		(24 "In11.Cu" signal "IN4")
		(26 "In12.Cu" signal "GND5")
		(28 "In13.Cu" signal "IN5")
		(30 "In14.Cu" signal "GND6")
		(32 "In15.Cu" signal "IN6")
		(34 "In16.Cu" signal "GND7")
		(2 "B.Cu" signal "BOTTOM")
		(9 "F.Adhes" user "F.Adhesive")
		(11 "B.Adhes" user "B.Adhesive")
		(13 "F.Paste" user "Package Geometry/Pastemask Top")
		(15 "B.Paste" user "Package Geometry/Pastemask Bottom")
		(5 "F.SilkS" user "Ref Des/Silkscreen Top")
		(7 "B.SilkS" user "Ref Des/Silkscreen Bottom")
		(1 "F.Mask" user "Board Geometry/Soldermask Top")
		(3 "B.Mask" user "Board Geometry/Soldermask Bottom")
		(17 "Dwgs.User" user "User.Drawings")
		(19 "Cmts.User" user "User.Comments")
		(21 "Eco1.User" user "User.Eco1")
		(23 "Eco2.User" user "User.Eco2")
		(25 "Edge.Cuts" user "Board Geometry/Outline")
		(27 "Margin" user)
		(31 "F.CrtYd" user "Package Geometry/Place Bound Top")
		(29 "B.CrtYd" user "Package Geometry/Place Bound Bottom")
		(35 "F.Fab" user "Ref Des/Assembly Top")
		(33 "B.Fab" user "Ref Des/Assembly Bottom")
	)
	(footprint ""
		(layer "F.Cu")
		(at 219.014294 -179.11318 180)
		(property "Reference" "R5502"
			(at 0 0 180)
			(layer "F.SilkS")
			(hide yes)
			(effects
				(font
					(size 1.27 1.27)
				)
			)
		)
		(property "Value" ""
			(at 0 0 180)
			(layer "F.Fab")
			(effects
				(font
					(size 1.27 1.27)
				)
			)
		)
		(duplicate_pad_numbers_are_jumpers no)
		(fp_line
			(start 0.7874 0.4064)
			(end -0.7874 0.4064)
			(stroke
				(width 0.1524)
				(type default)
			)
			(layer "F.SilkS")
		)
		(fp_line
			(start 0.7874 -0.4064)
			(end 0.7874 0.4064)
			(stroke
				(width 0.1524)
				(type default)
			)
			(layer "F.SilkS")
		)
		(fp_line
			(start -0.7874 0.4064)
			(end -0.7874 -0.4064)
			(stroke
				(width 0.1524)
				(type default)
			)
			(layer "F.SilkS")
		)
		(fp_line
			(start -0.7874 -0.4064)
			(end 0.7874 -0.4064)
			(stroke
				(width 0.1524)
				(type default)
			)
			(layer "F.SilkS")
		)
		(fp_line
			(start 0.67945 0.3048)
			(end 0.120396 0.3048)
			(stroke
				(width 0.1)
				(type default)
			)
			(layer "F.Fab")
		)
		(fp_line
			(start 0.67945 -0.3048)
			(end 0.67945 0.3048)
			(stroke
				(width 0.1)
				(type default)
			)
			(layer "F.Fab")
		)
		(fp_line
			(start 0.12065 -0.2794)
			(end 0.12065 -0.3048)
			(stroke
				(width 0.1)
				(type default)
			)
			(layer "F.Fab")
		)
		(fp_line
			(start 0.12065 -0.3048)
			(end 0.67945 -0.3048)
			(stroke
				(width 0.1)
				(type default)
			)
			(layer "F.Fab")
		)
		(fp_line
			(start 0.120396 0.3048)
			(end 0.120396 0.2794)
			(stroke
				(width 0.1)
				(type default)
			)
			(layer "F.Fab")
		)
		(fp_line
			(start 0.120396 0.2794)
			(end -0.12065 0.2794)
			(stroke
				(width 0.1)
				(type default)
			)
			(layer "F.Fab")
		)
		(fp_line
			(start -0.12065 0.3048)
			(end -0.67945 0.3048)
			(stroke
				(width 0.1)
				(type default)
			)
			(layer "F.Fab")
		)
		(fp_line
			(start -0.12065 0.2794)
			(end -0.12065 0.3048)
			(stroke
				(width 0.1)
				(type default)
			)
			(layer "F.Fab")
		)
		(fp_line
			(start -0.12065 -0.2794)
			(end 0.12065 -0.2794)
			(stroke
				(width 0.1)
				(type default)
			)
			(layer "F.Fab")
		)
		(fp_line
			(start -0.12065 -0.305054)
			(end -0.12065 -0.2794)
			(stroke
				(width 0.1)
				(type default)
			)
			(layer "F.Fab")
		)
		(fp_line
			(start -0.67945 0.3048)
			(end -0.67945 -0.305054)
			(stroke
				(width 0.1)
				(type default)
			)
			(layer "F.Fab")
		)
		(fp_line
			(start -0.67945 -0.305054)
			(end -0.12065 -0.305054)
			(stroke
				(width 0.1)
				(type default)
			)
			(layer "F.Fab")
		)
		(pad "1" smd circle
			(at -0.40005 0 180)
			(size 0 0)
			(layers "F.Cu" "F.Mask" "F.Paste")
			(net "RST_FW_BIC_PLTRST")
		)
		(pad "2" smd circle
			(at 0.40005 0 180)
			(size 0 0)
			(layers "F.Cu" "F.Mask" "F.Paste")
			(net "RST_FW_BIC_PLTRST_R")
		)
	)
	(footprint ""
		(layer "F.Cu")
		(at 175.0949 -97.718372 180)
		(property "Reference" "R201"
			(at 0 0 180)
			(layer "F.SilkS")
			(hide yes)
			(effects
				(font
					(size 1.27 1.27)
				)
			)
		)
		(property "Value" ""
			(at 0 0 180)
			(layer "F.Fab")
			(effects
				(font
					(size 1.27 1.27)
				)
			)
		)
		(duplicate_pad_numbers_are_jumpers no)
		(fp_line
			(start 0.7874 0.4064)
			(end -0.7874 0.4064)
			(stroke
				(width 0.1524)
				(type default)
			)
			(layer "F.SilkS")
		)
		(fp_line
			(start 0.7874 -0.4064)
			(end 0.7874 0.4064)
			(stroke
				(width 0.1524)
				(type default)
			)
			(layer "F.SilkS")
		)
		(fp_line
			(start -0.7874 0.4064)
			(end -0.7874 -0.4064)
			(stroke
				(width 0.1524)
				(type default)
			)
			(layer "F.SilkS")
		)
		(fp_line
			(start -0.7874 -0.4064)
			(end 0.7874 -0.4064)
			(stroke
				(width 0.1524)
				(type default)
			)
			(layer "F.SilkS")
		)
		(fp_line
			(start 0.67945 0.3048)
			(end 0.120396 0.3048)
			(stroke
				(width 0.1)
				(type default)
			)
			(layer "F.Fab")
		)
		(fp_line
			(start 0.67945 -0.3048)
			(end 0.67945 0.3048)
			(stroke
				(width 0.1)
				(type default)
			)
			(layer "F.Fab")
		)
		(fp_line
			(start 0.12065 -0.2794)
			(end 0.12065 -0.3048)
			(stroke
				(width 0.1)
				(type default)
			)
			(layer "F.Fab")
		)
		(fp_line
			(start 0.12065 -0.3048)
			(end 0.67945 -0.3048)
			(stroke
				(width 0.1)
				(type default)
			)
			(layer "F.Fab")
		)
		(fp_line
			(start 0.120396 0.3048)
			(end 0.120396 0.2794)
			(stroke
				(width 0.1)
				(type default)
			)
			(layer "F.Fab")
		)
		(fp_line
			(start 0.120396 0.2794)
			(end -0.12065 0.2794)
			(stroke
				(width 0.1)
				(type default)
			)
			(layer "F.Fab")
		)
		(fp_line
			(start -0.12065 0.3048)
			(end -0.67945 0.3048)
			(stroke
				(width 0.1)
				(type default)
			)
			(layer "F.Fab")
		)
		(fp_line
			(start -0.12065 0.2794)
			(end -0.12065 0.3048)
			(stroke
				(width 0.1)
				(type default)
			)
			(layer "F.Fab")
		)
		(fp_line
			(start -0.12065 -0.2794)
			(end 0.12065 -0.2794)
			(stroke
				(width 0.1)
				(type default)
			)
			(layer "F.Fab")
		)
		(fp_line
			(start -0.12065 -0.305054)
			(end -0.12065 -0.2794)
			(stroke
				(width 0.1)
				(type default)
			)
			(layer "F.Fab")
		)
		(fp_line
			(start -0.67945 0.3048)
			(end -0.67945 -0.305054)
			(stroke
				(width 0.1)
				(type default)
			)
			(layer "F.Fab")
		)
		(fp_line
			(start -0.67945 -0.305054)
			(end -0.12065 -0.305054)
			(stroke
				(width 0.1)
				(type default)
			)
			(layer "F.Fab")
		)
		(pad "1" smd circle
			(at -0.40005 0 180)
			(size 0 0)
			(layers "F.Cu" "F.Mask" "F.Paste")
			(net "RST_NIC3_PERST3_R_N")
		)
		(pad "2" smd circle
			(at 0.40005 0 180)
			(size 0 0)
			(layers "F.Cu" "F.Mask" "F.Paste")
			(net "RST_HP_NIC3_BUF_N")
		)
	)
	(footprint ""
		(layer "F.Cu")
		(at 418.226494 -25.432004 -90)
		(property "Reference" "C979"
			(at 0 0 270)
			(layer "F.SilkS")
			(hide yes)
			(effects
				(font
					(size 1.27 1.27)
				)
			)
		)
		(property "Value" ""
			(at 0 0 270)
			(layer "F.Fab")
			(effects
				(font
					(size 1.27 1.27)
				)
			)
		)
		(duplicate_pad_numbers_are_jumpers no)
		(fp_line
			(start -0.7874 0.4064)
			(end -0.7874 -0.4064)
			(stroke
				(width 0.1524)
				(type default)
			)
			(layer "F.SilkS")
		)
		(fp_line
			(start 0.7874 0.4064)
			(end -0.7874 0.4064)
			(stroke
				(width 0.1524)
				(type default)
			)
			(layer "F.SilkS")
		)
		(fp_line
			(start -0.7874 -0.4064)
			(end 0.7874 -0.4064)
			(stroke
				(width 0.1524)
				(type default)
			)
			(layer "F.SilkS")
		)
		(fp_line
			(start 0.7874 -0.4064)
			(end 0.7874 0.4064)
			(stroke
				(width 0.1524)
				(type default)
			)
			(layer "F.SilkS")
		)
		(fp_line
			(start -0.67945 0.3048)
			(end -0.67945 -0.305054)
			(stroke
				(width 0.1)
				(type default)
			)
			(layer "F.Fab")
		)
		(fp_line
			(start -0.12065 0.3048)
			(end -0.67945 0.3048)
			(stroke
				(width 0.1)
				(type default)
			)
			(layer "F.Fab")
		)
		(fp_line
			(start 0.120396 0.3048)
			(end 0.120396 0.2794)
			(stroke
				(width 0.1)
				(type default)
			)
			(layer "F.Fab")
		)
		(fp_line
			(start 0.67945 0.3048)
			(end 0.120396 0.3048)
			(stroke
				(width 0.1)
				(type default)
			)
			(layer "F.Fab")
		)
		(fp_line
			(start -0.12065 0.2794)
			(end -0.12065 0.3048)
			(stroke
				(width 0.1)
				(type default)
			)
			(layer "F.Fab")
		)
		(fp_line
			(start 0.120396 0.2794)
			(end -0.12065 0.2794)
			(stroke
				(width 0.1)
				(type default)
			)
			(layer "F.Fab")
		)
		(fp_line
			(start -0.12065 -0.2794)
			(end 0.12065 -0.2794)
			(stroke
				(width 0.1)
				(type default)
			)
			(layer "F.Fab")
		)
		(fp_line
			(start 0.12065 -0.2794)
			(end 0.12065 -0.3048)
			(stroke
				(width 0.1)
				(type default)
			)
			(layer "F.Fab")
		)
		(fp_line
			(start 0.12065 -0.3048)
			(end 0.67945 -0.3048)
			(stroke
				(width 0.1)
				(type default)
			)
			(layer "F.Fab")
		)
		(fp_line
			(start 0.67945 -0.3048)
			(end 0.67945 0.3048)
			(stroke
				(width 0.1)
				(type default)
			)
			(layer "F.Fab")
		)
		(fp_line
			(start -0.67945 -0.305054)
			(end -0.12065 -0.305054)
			(stroke
				(width 0.1)
				(type default)
			)
			(layer "F.Fab")
		)
		(fp_line
			(start -0.12065 -0.305054)
			(end -0.12065 -0.2794)
			(stroke
				(width 0.1)
				(type default)
			)
			(layer "F.Fab")
		)
		(pad "1" smd circle
			(at -0.40005 0 270)
			(size 0 0)
			(layers "F.Cu" "F.Mask" "F.Paste")
			(net "GND")
		)
		(pad "2" smd circle
			(at 0.40005 0 270)
			(size 0 0)
			(layers "F.Cu" "F.Mask" "F.Paste")
			(net "P3V3_SSD14")
		)
	)
	(footprint ""
		(layer "F.Cu")
		(at 284.443678 -46.90491)
		(property "Reference" "R607"
			(at 0 0 0)
			(layer "F.SilkS")
			(hide yes)
			(effects
				(font
					(size 1.27 1.27)
				)
			)
		)
		(property "Value" ""
			(at 0 0 0)
			(layer "F.Fab")
			(effects
				(font
					(size 1.27 1.27)
				)
			)
		)
		(duplicate_pad_numbers_are_jumpers no)
		(fp_line
			(start -0.7874 -0.4064)
			(end 0.7874 -0.4064)
			(stroke
				(width 0.1524)
				(type default)
			)
			(layer "F.SilkS")
		)
		(fp_line
			(start -0.7874 0.4064)
			(end -0.7874 -0.4064)
			(stroke
				(width 0.1524)
				(type default)
			)
			(layer "F.SilkS")
		)
		(fp_line
			(start 0.7874 -0.4064)
			(end 0.7874 0.4064)
			(stroke
				(width 0.1524)
				(type default)
			)
			(layer "F.SilkS")
		)
		(fp_line
			(start 0.7874 0.4064)
			(end -0.7874 0.4064)
			(stroke
				(width 0.1524)
				(type default)
			)
			(layer "F.SilkS")
		)
		(fp_line
			(start -0.67945 -0.305054)
			(end -0.12065 -0.305054)
			(stroke
				(width 0.1)
				(type default)
			)
			(layer "F.Fab")
		)
		(fp_line
			(start -0.67945 0.3048)
			(end -0.67945 -0.305054)
			(stroke
				(width 0.1)
				(type default)
			)
			(layer "F.Fab")
		)
		(fp_line
			(start -0.12065 -0.305054)
			(end -0.12065 -0.2794)
			(stroke
				(width 0.1)
				(type default)
			)
			(layer "F.Fab")
		)
		(fp_line
			(start -0.12065 -0.2794)
			(end 0.12065 -0.2794)
			(stroke
				(width 0.1)
				(type default)
			)
			(layer "F.Fab")
		)
		(fp_line
			(start -0.12065 0.2794)
			(end -0.12065 0.3048)
			(stroke
				(width 0.1)
				(type default)
			)
			(layer "F.Fab")
		)
		(fp_line
			(start -0.12065 0.3048)
			(end -0.67945 0.3048)
			(stroke
				(width 0.1)
				(type default)
			)
			(layer "F.Fab")
		)
		(fp_line
			(start 0.120396 0.2794)
			(end -0.12065 0.2794)
			(stroke
				(width 0.1)
				(type default)
			)
			(layer "F.Fab")
		)
		(fp_line
			(start 0.120396 0.3048)
			(end 0.120396 0.2794)
			(stroke
				(width 0.1)
				(type default)
			)
			(layer "F.Fab")
		)
		(fp_line
			(start 0.12065 -0.3048)
			(end 0.67945 -0.3048)
			(stroke
				(width 0.1)
				(type default)
			)
			(layer "F.Fab")
		)
		(fp_line
			(start 0.12065 -0.2794)
			(end 0.12065 -0.3048)
			(stroke
				(width 0.1)
				(type default)
			)
			(layer "F.Fab")
		)
		(fp_line
			(start 0.67945 -0.3048)
			(end 0.67945 0.3048)
			(stroke
				(width 0.1)
				(type default)
			)
			(layer "F.Fab")
		)
		(fp_line
			(start 0.67945 0.3048)
			(end 0.120396 0.3048)
			(stroke
				(width 0.1)
				(type default)
			)
			(layer "F.Fab")
		)
		(pad "1" smd circle
			(at -0.40005 0)
			(size 0 0)
			(layers "F.Cu" "F.Mask" "F.Paste")
			(net "SSD9_ADC_ALERT_N")
		)
		(pad "2" smd circle
			(at 0.40005 0)
			(size 0 0)
			(layers "F.Cu" "F.Mask" "F.Paste")
			(net "SSD_8_15_ADC_ALERT_N")
		)
	)
	(footprint ""
		(layer "F.Cu")
		(at 489.627164 -528.154392 180)
		(property "Reference" "PEX0_HS"
			(at 0.127 -0.593598 0)
			(unlocked yes)
			(layer "F.SilkS")
			(effects
				(font
					(size 0.254 0.127)
					(thickness 0.000001)
				)
			)
		)
		(property "Value" ""
			(at 0 0 180)
			(layer "F.Fab")
			(effects
				(font
					(size 1.27 1.27)
				)
			)
		)
		(duplicate_pad_numbers_are_jumpers no)
		(pad "1" smd circle
			(at 0 0 180)
			(size 0.762 0.762)
			(layers "F.Cu" "F.Mask" "F.Paste")
			(net "Net_9124")
		)
	)
	(footprint ""
		(layer "F.Cu")
		(at 438.939432 -293.47287 -90)
		(property "Reference" "U316"
			(at -0.309118 -5.440172 90)
			(unlocked yes)
			(layer "F.SilkS")
			(effects
				(font
					(size 0.7874 0.5842)
					(thickness 0.1524)
				)
			)
		)
		(property "Value" ""
			(at 0 0 270)
			(layer "F.Fab")
			(effects
				(font
					(size 1.27 1.27)
				)
			)
		)
		(duplicate_pad_numbers_are_jumpers no)
		(fp_line
			(start -1.463548 1.549908)
			(end -1.463548 -1.549908)
			(stroke
				(width 0.1524)
				(type default)
			)
			(layer "F.SilkS")
		)
		(fp_line
			(start 1.463548 1.549908)
			(end -1.463548 1.549908)
			(stroke
				(width 0.1524)
				(type default)
			)
			(layer "F.SilkS")
		)
		(fp_line
			(start 0 -0.762)
			(end 0.762 -1.549908)
			(stroke
				(width 0.1524)
				(type default)
			)
			(layer "F.SilkS")
		)
		(fp_line
			(start -1.463548 -1.549908)
			(end -0.787908 -1.549908)
			(stroke
				(width 0.1524)
				(type default)
			)
			(layer "F.SilkS")
		)
		(fp_line
			(start -0.787908 -1.549908)
			(end 0 -0.762)
			(stroke
				(width 0.1524)
				(type default)
			)
			(layer "F.SilkS")
		)
		(fp_line
			(start 0.762 -1.549908)
			(end 1.463548 -1.549908)
			(stroke
				(width 0.1524)
				(type default)
			)
			(layer "F.SilkS")
		)
		(fp_line
			(start 1.463548 -1.549908)
			(end 1.463548 1.549908)
			(stroke
				(width 0.1524)
				(type default)
			)
			(layer "F.SilkS")
		)
		(fp_poly
			(pts
				(xy -3.4798 -1.359916) (xy -2.86004 -1.050036) (xy -3.4798 -0.740156)
			)
			(stroke
				(width 0)
				(type default)
			)
			(fill yes)
			(layer "F.SilkS")
		)
		(fp_line
			(start -1.549908 1.549908)
			(end -1.549908 -1.549908)
			(stroke
				(width 0.1)
				(type default)
			)
			(layer "F.Fab")
		)
		(fp_line
			(start 1.549908 1.549908)
			(end -1.549908 1.549908)
			(stroke
				(width 0.1)
				(type default)
			)
			(layer "F.Fab")
		)
		(fp_line
			(start -1.549908 -1.549908)
			(end 1.549908 -1.549908)
			(stroke
				(width 0.1)
				(type default)
			)
			(layer "F.Fab")
		)
		(fp_line
			(start 1.549908 -1.549908)
			(end 1.549908 1.549908)
			(stroke
				(width 0.1)
				(type default)
			)
			(layer "F.Fab")
		)
		(fp_poly
			(pts
				(xy -3.4798 -1.359916) (xy -2.86004 -1.050036) (xy -3.4798 -0.740156)
			)
			(stroke
				(width 0)
				(type default)
			)
			(fill yes)
			(layer "F.Fab")
		)
		(pad "1" smd rect
			(at -2.175002 -1.050036)
			(size 0.6096 1.1684)
			(layers "F.Cu" "F.Mask" "F.Paste")
			(net "P1V8_PEX")
		)
		(pad "2" smd rect
			(at -2.175002 -0.32512)
			(size 0.4318 1.1684)
			(layers "F.Cu" "F.Mask" "F.Paste")
			(net "I2C_PEX3_HOST_R_SCL")
		)
		(pad "3" smd rect
			(at -2.175002 0.32512)
			(size 0.4318 1.1684)
			(layers "F.Cu" "F.Mask" "F.Paste")
			(net "I2C_PEX3_HOST_R_SDA")
		)
		(pad "4" smd rect
			(at -2.175002 1.050036)
			(size 0.6096 1.1684)
			(layers "F.Cu" "F.Mask" "F.Paste")
			(net "GND")
		)
		(pad "5" smd rect
			(at 2.175002 1.050036)
			(size 0.6096 1.1684)
			(layers "F.Cu" "F.Mask" "F.Paste")
			(net "PWRGD_P1V8_PEX3_R")
		)
		(pad "6" smd rect
			(at 2.175002 0.32512)
			(size 0.4318 1.1684)
			(layers "F.Cu" "F.Mask" "F.Paste")
			(net "SMB_PEX3_HOST_LS_SDA")
		)
		(pad "7" smd rect
			(at 2.175002 -0.32512)
			(size 0.4318 1.1684)
			(layers "F.Cu" "F.Mask" "F.Paste")
			(net "SMB_PEX3_HOST_LS_SCL")
		)
		(pad "8" smd rect
			(at 2.175002 -1.050036)
			(size 0.6096 1.1684)
			(layers "F.Cu" "F.Mask" "F.Paste")
			(net "P3V3_AUX")
		)
	)
	(footprint ""
		(layer "F.Cu")
		(at 145.273268 -392.62939 -90)
		(property "Reference" "C4078"
			(at 0 0 270)
			(layer "F.SilkS")
			(hide yes)
			(effects
				(font
					(size 1.27 1.27)
				)
			)
		)
		(property "Value" ""
			(at 0 0 270)
			(layer "F.Fab")
			(effects
				(font
					(size 1.27 1.27)
				)
			)
		)
		(duplicate_pad_numbers_are_jumpers no)
		(fp_line
			(start -0.7874 0.4064)
			(end -0.7874 -0.4064)
			(stroke
				(width 0.1524)
				(type default)
			)
			(layer "F.SilkS")
		)
		(fp_line
			(start 0.7874 0.4064)
			(end -0.7874 0.4064)
			(stroke
				(width 0.1524)
				(type default)
			)
			(layer "F.SilkS")
		)
		(fp_line
			(start -0.7874 -0.4064)
			(end 0.7874 -0.4064)
			(stroke
				(width 0.1524)
				(type default)
			)
			(layer "F.SilkS")
		)
		(fp_line
			(start 0.7874 -0.4064)
			(end 0.7874 0.4064)
			(stroke
				(width 0.1524)
				(type default)
			)
			(layer "F.SilkS")
		)
		(fp_line
			(start -0.67945 0.3048)
			(end -0.67945 -0.305054)
			(stroke
				(width 0.1)
				(type default)
			)
			(layer "F.Fab")
		)
		(fp_line
			(start -0.12065 0.3048)
			(end -0.67945 0.3048)
			(stroke
				(width 0.1)
				(type default)
			)
			(layer "F.Fab")
		)
		(fp_line
			(start 0.120396 0.3048)
			(end 0.120396 0.2794)
			(stroke
				(width 0.1)
				(type default)
			)
			(layer "F.Fab")
		)
		(fp_line
			(start 0.67945 0.3048)
			(end 0.120396 0.3048)
			(stroke
				(width 0.1)
				(type default)
			)
			(layer "F.Fab")
		)
		(fp_line
			(start -0.12065 0.2794)
			(end -0.12065 0.3048)
			(stroke
				(width 0.1)
				(type default)
			)
			(layer "F.Fab")
		)
		(fp_line
			(start 0.120396 0.2794)
			(end -0.12065 0.2794)
			(stroke
				(width 0.1)
				(type default)
			)
			(layer "F.Fab")
		)
		(fp_line
			(start -0.12065 -0.2794)
			(end 0.12065 -0.2794)
			(stroke
				(width 0.1)
				(type default)
			)
			(layer "F.Fab")
		)
		(fp_line
			(start 0.12065 -0.2794)
			(end 0.12065 -0.3048)
			(stroke
				(width 0.1)
				(type default)
			)
			(layer "F.Fab")
		)
		(fp_line
			(start 0.12065 -0.3048)
			(end 0.67945 -0.3048)
			(stroke
				(width 0.1)
				(type default)
			)
			(layer "F.Fab")
		)
		(fp_line
			(start 0.67945 -0.3048)
			(end 0.67945 0.3048)
			(stroke
				(width 0.1)
				(type default)
			)
			(layer "F.Fab")
		)
		(fp_line
			(start -0.67945 -0.305054)
			(end -0.12065 -0.305054)
			(stroke
				(width 0.1)
				(type default)
			)
			(layer "F.Fab")
		)
		(fp_line
			(start -0.12065 -0.305054)
			(end -0.12065 -0.2794)
			(stroke
				(width 0.1)
				(type default)
			)
			(layer "F.Fab")
		)
		(pad "1" smd circle
			(at -0.40005 0 270)
			(size 0 0)
			(layers "F.Cu" "F.Mask" "F.Paste")
			(net "GND")
		)
		(pad "2" smd circle
			(at 0.40005 0 270)
			(size 0 0)
			(layers "F.Cu" "F.Mask" "F.Paste")
			(net "GPU_FPGA_BOOT_EN")
		)
	)
)
